(kicad_pcb
	(version 20260206)
	(generator "pcbnew")
	(generator_version "10.0")
	(general
		(thickness 1.6)
		(legacy_teardrops no)
	)
	(paper "A4")
	(title_block
		(title "v1-tray-backplane — T6M_tray_BP_c_1023_1120.brd")
		(comment 1 "Open CloudServer (Microsoft) / footprints 113-122 of 170")
	)
	(layers
		(0 "F.Cu" signal "TOP")
		(4 "In1.Cu" signal "GND")
		(6 "In2.Cu" signal "IN1")
		(8 "In3.Cu" signal "VCC")
		(10 "In4.Cu" signal "VCC1")
		(12 "In5.Cu" signal "IN2")
		(14 "In6.Cu" signal "GND1")
		(2 "B.Cu" signal "BOTTOM")
		(9 "F.Adhes" user "F.Adhesive")
		(11 "B.Adhes" user "B.Adhesive")
		(13 "F.Paste" user "Package Geometry/Pastemask Top")
		(15 "B.Paste" user "Package Geometry/Pastemask Bottom")
		(5 "F.SilkS" user "Ref Des/Silkscreen Top")
		(7 "B.SilkS" user "Ref Des/Silkscreen Bottom")
		(1 "F.Mask" user "Board Geometry/Soldermask Top")
		(3 "B.Mask" user "Board Geometry/Soldermask Bottom")
		(17 "Dwgs.User" user "User.Drawings")
		(19 "Cmts.User" user "User.Comments")
		(21 "Eco1.User" user "User.Eco1")
		(23 "Eco2.User" user "User.Eco2")
		(25 "Edge.Cuts" user "Board Geometry/Outline")
		(27 "Margin" user)
		(31 "F.CrtYd" user "Package Geometry/Place Bound Top")
		(29 "B.CrtYd" user "Package Geometry/Place Bound Bottom")
		(35 "F.Fab" user "Ref Des/Assembly Top")
		(33 "B.Fab" user "Ref Des/Assembly Bottom")
	)
	(footprint ""
		(layer "F.Cu")
		(at 375.82856 -26.227278 180)
		(property "Reference" "R27"
			(at -33.78708 -16.853408 0)
			(unlocked yes)
			(layer "F.SilkS")
			(effects
				(font
					(size 0.7874 0.5842)
					(thickness 0.1524)
				)
				(justify left)
			)
		)
		(property "Value" ""
			(at 0 0 180)
			(layer "F.Fab")
			(effects
				(font
					(size 1.27 1.27)
				)
			)
		)
		(duplicate_pad_numbers_are_jumpers no)
		(fp_line
			(start 0.7874 0.4064)
			(end -0.7874 0.4064)
			(stroke
				(width 0.1524)
				(type default)
			)
			(layer "F.SilkS")
		)
		(fp_line
			(start 0.7874 -0.4064)
			(end 0.7874 0.4064)
			(stroke
				(width 0.1524)
				(type default)
			)
			(layer "F.SilkS")
		)
		(fp_line
			(start -0.7874 0.4064)
			(end -0.7874 -0.4064)
			(stroke
				(width 0.1524)
				(type default)
			)
			(layer "F.SilkS")
		)
		(fp_line
			(start -0.7874 -0.4064)
			(end 0.7874 -0.4064)
			(stroke
				(width 0.1524)
				(type default)
			)
			(layer "F.SilkS")
		)
		(fp_poly
			(pts
				(xy -0.508 0.2794) (xy -0.508 0.2286) (xy -0.635 0.2286) (xy -0.635 -0.254) (xy -0.5334 -0.254)
				(xy -0.5334 -0.2794) (xy 0.5334 -0.2794) (xy 0.5334 -0.254) (xy 0.635 -0.254) (xy 0.635 0.254) (xy 0.5334 0.254)
				(xy 0.5334 0.2794)
			)
			(stroke
				(width 0)
				(type default)
			)
			(fill no)
			(layer "F.CrtYd")
		)
		(pad "1" smd rect
			(at 0.40005 0 180)
			(size 0.4572 0.508)
			(layers "F.Cu" "F.Mask" "F.Paste")
			(net "P3V3_BLAD2")
		)
		(pad "2" smd rect
			(at -0.40005 0 180)
			(size 0.4572 0.508)
			(layers "F.Cu" "F.Mask" "F.Paste")
			(net "ENET10G_3_RS0")
		)
	)
	(footprint ""
		(layer "F.Cu")
		(at 25.841706 -16.354552 -90)
		(property "Reference" "R33"
			(at 3.727704 -0.16764 90)
			(unlocked yes)
			(layer "F.SilkS")
			(effects
				(font
					(size 0.7874 0.5842)
					(thickness 0.1524)
				)
				(justify left)
			)
		)
		(property "Value" ""
			(at 0 0 270)
			(layer "F.Fab")
			(effects
				(font
					(size 1.27 1.27)
				)
			)
		)
		(duplicate_pad_numbers_are_jumpers no)
		(fp_line
			(start -0.7874 0.4064)
			(end -0.7874 -0.4064)
			(stroke
				(width 0.1524)
				(type default)
			)
			(layer "F.SilkS")
		)
		(fp_line
			(start 0.7874 0.4064)
			(end -0.7874 0.4064)
			(stroke
				(width 0.1524)
				(type default)
			)
			(layer "F.SilkS")
		)
		(fp_line
			(start -0.7874 -0.4064)
			(end 0.7874 -0.4064)
			(stroke
				(width 0.1524)
				(type default)
			)
			(layer "F.SilkS")
		)
		(fp_line
			(start 0.7874 -0.4064)
			(end 0.7874 0.4064)
			(stroke
				(width 0.1524)
				(type default)
			)
			(layer "F.SilkS")
		)
		(fp_poly
			(pts
				(xy -0.508 0.2794) (xy -0.508 0.2286) (xy -0.635 0.2286) (xy -0.635 -0.254) (xy -0.5334 -0.254)
				(xy -0.5334 -0.2794) (xy 0.5334 -0.2794) (xy 0.5334 -0.254) (xy 0.635 -0.254) (xy 0.635 0.254) (xy 0.5334 0.254)
				(xy 0.5334 0.2794)
			)
			(stroke
				(width 0)
				(type default)
			)
			(fill no)
			(layer "F.CrtYd")
		)
		(pad "1" smd rect
			(at 0.40005 0 270)
			(size 0.4572 0.508)
			(layers "F.Cu" "F.Mask" "F.Paste")
			(net "GND")
		)
		(pad "2" smd rect
			(at -0.40005 0 270)
			(size 0.4572 0.508)
			(layers "F.Cu" "F.Mask" "F.Paste")
			(net "PS_EN_PSU_N")
		)
	)
	(footprint ""
		(layer "F.Cu")
		(at 90.997786 -23.442676 -90)
		(property "Reference" "C3"
			(at -0.612648 5.55752 90)
			(unlocked yes)
			(layer "F.SilkS")
			(effects
				(font
					(size 0.7874 0.5842)
					(thickness 0.1524)
				)
				(justify left)
			)
		)
		(property "Value" ""
			(at 0 0 270)
			(layer "F.Fab")
			(effects
				(font
					(size 1.27 1.27)
				)
			)
		)
		(duplicate_pad_numbers_are_jumpers no)
		(fp_line
			(start -0.7874 0.4064)
			(end -0.7874 -0.4064)
			(stroke
				(width 0.1524)
				(type default)
			)
			(layer "F.SilkS")
		)
		(fp_line
			(start 0.7874 0.4064)
			(end -0.7874 0.4064)
			(stroke
				(width 0.1524)
				(type default)
			)
			(layer "F.SilkS")
		)
		(fp_line
			(start 0 0.381)
			(end 0 -0.381)
			(stroke
				(width 0.1524)
				(type default)
			)
			(layer "F.SilkS")
		)
		(fp_line
			(start -0.7874 -0.4064)
			(end 0.7874 -0.4064)
			(stroke
				(width 0.1524)
				(type default)
			)
			(layer "F.SilkS")
		)
		(fp_line
			(start 0.7874 -0.4064)
			(end 0.7874 0.4064)
			(stroke
				(width 0.1524)
				(type default)
			)
			(layer "F.SilkS")
		)
		(fp_poly
			(pts
				(xy -0.5334 0.254) (xy -0.635 0.254) (xy -0.635 0.2286) (xy -0.635 -0.254) (xy -0.5334 -0.254) (xy -0.5334 -0.2794)
				(xy 0.5334 -0.2794) (xy 0.5334 -0.254) (xy 0.635 -0.254) (xy 0.635 0.254) (xy 0.5334 0.254) (xy 0.5334 0.2794)
				(xy -0.508 0.2794) (xy -0.5334 0.2794)
			)
			(stroke
				(width 0)
				(type default)
			)
			(fill no)
			(layer "F.CrtYd")
		)
		(pad "1" smd rect
			(at 0.40005 0 270)
			(size 0.4572 0.508)
			(layers "F.Cu" "F.Mask" "F.Paste")
			(net "P12V")
		)
		(pad "2" smd rect
			(at -0.40005 0 270)
			(size 0.4572 0.508)
			(layers "F.Cu" "F.Mask" "F.Paste")
			(net "GND")
		)
	)
	(footprint ""
		(layer "F.Cu")
		(at 366.4204 -3.1242 90)
		(property "Reference" "C25"
			(at -2.3622 2.270252 90)
			(unlocked yes)
			(layer "F.SilkS")
			(effects
				(font
					(size 0.7874 0.5842)
					(thickness 0.1524)
				)
				(justify left)
			)
		)
		(property "Value" ""
			(at 0 0 90)
			(layer "F.Fab")
			(effects
				(font
					(size 1.27 1.27)
				)
			)
		)
		(duplicate_pad_numbers_are_jumpers no)
		(fp_line
			(start 0.7874 -0.4064)
			(end 0.7874 0.4064)
			(stroke
				(width 0.1524)
				(type default)
			)
			(layer "F.SilkS")
		)
		(fp_line
			(start -0.7874 -0.4064)
			(end 0.7874 -0.4064)
			(stroke
				(width 0.1524)
				(type default)
			)
			(layer "F.SilkS")
		)
		(fp_line
			(start 0 0.381)
			(end 0 -0.381)
			(stroke
				(width 0.1524)
				(type default)
			)
			(layer "F.SilkS")
		)
		(fp_line
			(start 0.7874 0.4064)
			(end -0.7874 0.4064)
			(stroke
				(width 0.1524)
				(type default)
			)
			(layer "F.SilkS")
		)
		(fp_line
			(start -0.7874 0.4064)
			(end -0.7874 -0.4064)
			(stroke
				(width 0.1524)
				(type default)
			)
			(layer "F.SilkS")
		)
		(fp_poly
			(pts
				(xy -0.5334 0.254) (xy -0.635 0.254) (xy -0.635 0.2286) (xy -0.635 -0.254) (xy -0.5334 -0.254) (xy -0.5334 -0.2794)
				(xy 0.5334 -0.2794) (xy 0.5334 -0.254) (xy 0.635 -0.254) (xy 0.635 0.254) (xy 0.5334 0.254) (xy 0.5334 0.2794)
				(xy -0.508 0.2794) (xy -0.5334 0.2794)
			)
			(stroke
				(width 0)
				(type default)
			)
			(fill no)
			(layer "F.CrtYd")
		)
		(pad "1" smd rect
			(at 0.40005 0 90)
			(size 0.4572 0.508)
			(layers "F.Cu" "F.Mask" "F.Paste")
			(net "P3V3_10G_3_VCCT")
		)
		(pad "2" smd rect
			(at -0.40005 0 90)
			(size 0.4572 0.508)
			(layers "F.Cu" "F.Mask" "F.Paste")
			(net "GND")
		)
	)
	(footprint ""
		(layer "F.Cu")
		(at 157.781752 -25.439878)
		(property "Reference" "R42"
			(at 33.5534 17.942052 0)
			(unlocked yes)
			(layer "F.SilkS")
			(effects
				(font
					(size 0.7874 0.5842)
					(thickness 0.1524)
				)
				(justify left)
			)
		)
		(property "Value" ""
			(at 0 0 0)
			(layer "F.Fab")
			(effects
				(font
					(size 1.27 1.27)
				)
			)
		)
		(duplicate_pad_numbers_are_jumpers no)
		(fp_line
			(start -0.7874 -0.4064)
			(end 0.7874 -0.4064)
			(stroke
				(width 0.1524)
				(type default)
			)
			(layer "F.SilkS")
		)
		(fp_line
			(start -0.7874 0.4064)
			(end -0.7874 -0.4064)
			(stroke
				(width 0.1524)
				(type default)
			)
			(layer "F.SilkS")
		)
		(fp_line
			(start 0.7874 -0.4064)
			(end 0.7874 0.4064)
			(stroke
				(width 0.1524)
				(type default)
			)
			(layer "F.SilkS")
		)
		(fp_line
			(start 0.7874 0.4064)
			(end -0.7874 0.4064)
			(stroke
				(width 0.1524)
				(type default)
			)
			(layer "F.SilkS")
		)
		(fp_poly
			(pts
				(xy -0.508 0.2794) (xy -0.508 0.2286) (xy -0.635 0.2286) (xy -0.635 -0.254) (xy -0.5334 -0.254)
				(xy -0.5334 -0.2794) (xy 0.5334 -0.2794) (xy 0.5334 -0.254) (xy 0.635 -0.254) (xy 0.635 0.254) (xy 0.5334 0.254)
				(xy 0.5334 0.2794)
			)
			(stroke
				(width 0)
				(type default)
			)
			(fill no)
			(layer "F.CrtYd")
		)
		(pad "1" smd rect
			(at 0.40005 0)
			(size 0.4572 0.508)
			(layers "F.Cu" "F.Mask" "F.Paste")
			(net "GND")
		)
		(pad "2" smd rect
			(at -0.40005 0)
			(size 0.4572 0.508)
			(layers "F.Cu" "F.Mask" "F.Paste")
			(net "ENET10G_1_RS0")
		)
	)
	(footprint ""
		(layer "F.Cu")
		(at 102.5144 -2.921 90)
		(property "Reference" "C24"
			(at -2.3622 -4.917948 90)
			(unlocked yes)
			(layer "F.SilkS")
			(effects
				(font
					(size 0.7874 0.5842)
					(thickness 0.1524)
				)
				(justify left)
			)
		)
		(property "Value" ""
			(at 0 0 90)
			(layer "F.Fab")
			(effects
				(font
					(size 1.27 1.27)
				)
			)
		)
		(duplicate_pad_numbers_are_jumpers no)
		(fp_line
			(start 0.7874 -0.4064)
			(end 0.7874 0.4064)
			(stroke
				(width 0.1524)
				(type default)
			)
			(layer "F.SilkS")
		)
		(fp_line
			(start -0.7874 -0.4064)
			(end 0.7874 -0.4064)
			(stroke
				(width 0.1524)
				(type default)
			)
			(layer "F.SilkS")
		)
		(fp_line
			(start 0 0.381)
			(end 0 -0.381)
			(stroke
				(width 0.1524)
				(type default)
			)
			(layer "F.SilkS")
		)
		(fp_line
			(start 0.7874 0.4064)
			(end -0.7874 0.4064)
			(stroke
				(width 0.1524)
				(type default)
			)
			(layer "F.SilkS")
		)
		(fp_line
			(start -0.7874 0.4064)
			(end -0.7874 -0.4064)
			(stroke
				(width 0.1524)
				(type default)
			)
			(layer "F.SilkS")
		)
		(fp_poly
			(pts
				(xy -0.5334 0.254) (xy -0.635 0.254) (xy -0.635 0.2286) (xy -0.635 -0.254) (xy -0.5334 -0.254) (xy -0.5334 -0.2794)
				(xy 0.5334 -0.2794) (xy 0.5334 -0.254) (xy 0.635 -0.254) (xy 0.635 0.254) (xy 0.5334 0.254) (xy 0.5334 0.2794)
				(xy -0.508 0.2794) (xy -0.5334 0.2794)
			)
			(stroke
				(width 0)
				(type default)
			)
			(fill no)
			(layer "F.CrtYd")
		)
		(pad "1" smd rect
			(at 0.40005 0 90)
			(size 0.4572 0.508)
			(layers "F.Cu" "F.Mask" "F.Paste")
			(net "P3V3_10G_2_VCCR")
		)
		(pad "2" smd rect
			(at -0.40005 0 90)
			(size 0.4572 0.508)
			(layers "F.Cu" "F.Mask" "F.Paste")
			(net "GND")
		)
	)
	(footprint ""
		(layer "F.Cu")
		(at 377.8504 -35.433 90)
		(property "Reference" "L7"
			(at -21.463 33.70707 90)
			(unlocked yes)
			(layer "F.SilkS")
			(effects
				(font
					(size 0.7874 0.5842)
					(thickness 0.1524)
				)
				(justify left)
			)
		)
		(property "Value" ""
			(at 0 0 90)
			(layer "F.Fab")
			(effects
				(font
					(size 1.27 1.27)
				)
			)
		)
		(duplicate_pad_numbers_are_jumpers no)
		(fp_line
			(start -1.905 -0.8636)
			(end 1.905 -0.8636)
			(stroke
				(width 0.1524)
				(type default)
			)
			(layer "F.SilkS")
		)
		(fp_line
			(start 1.905 0.8382)
			(end 1.905 -0.8382)
			(stroke
				(width 0.1524)
				(type default)
			)
			(layer "F.SilkS")
		)
		(fp_line
			(start 0.127 0.8382)
			(end 0.127 -0.8382)
			(stroke
				(width 0.1524)
				(type default)
			)
			(layer "F.SilkS")
		)
		(fp_line
			(start -0.127 0.8382)
			(end -0.127 -0.8382)
			(stroke
				(width 0.1524)
				(type default)
			)
			(layer "F.SilkS")
		)
		(fp_line
			(start -1.905 0.8382)
			(end -1.905 -0.8382)
			(stroke
				(width 0.1524)
				(type default)
			)
			(layer "F.SilkS")
		)
		(fp_line
			(start 1.905 0.8636)
			(end -1.905 0.8636)
			(stroke
				(width 0.1524)
				(type default)
			)
			(layer "F.SilkS")
		)
		(fp_rect
			(start -1.524 0.7112)
			(end 1.524 -0.7366)
			(stroke
				(width 0)
				(type default)
			)
			(fill no)
			(layer "F.CrtYd")
		)
		(pad "1" smd rect
			(at 0.94996 0 90)
			(size 1.1176 1.3716)
			(layers "F.Cu" "F.Mask" "F.Paste")
			(net "P3V3_10G_3_VCCR_L")
		)
		(pad "2" smd rect
			(at -0.94996 0 90)
			(size 1.1176 1.3716)
			(layers "F.Cu" "F.Mask" "F.Paste")
			(net "P3V3_10G_3_VCCR")
		)
	)
	(footprint ""
		(layer "F.Cu")
		(at 156.959046 -34.3154 90)
		(property "Reference" "L3"
			(at -22.8346 33.770062 90)
			(unlocked yes)
			(layer "F.SilkS")
			(effects
				(font
					(size 0.7874 0.5842)
					(thickness 0.1524)
				)
				(justify left)
			)
		)
		(property "Value" ""
			(at 0 0 90)
			(layer "F.Fab")
			(effects
				(font
					(size 1.27 1.27)
				)
			)
		)
		(duplicate_pad_numbers_are_jumpers no)
		(fp_line
			(start -1.905 -0.8636)
			(end 1.905 -0.8636)
			(stroke
				(width 0.1524)
				(type default)
			)
			(layer "F.SilkS")
		)
		(fp_line
			(start 1.905 0.8382)
			(end 1.905 -0.8382)
			(stroke
				(width 0.1524)
				(type default)
			)
			(layer "F.SilkS")
		)
		(fp_line
			(start 0.127 0.8382)
			(end 0.127 -0.8382)
			(stroke
				(width 0.1524)
				(type default)
			)
			(layer "F.SilkS")
		)
		(fp_line
			(start -0.127 0.8382)
			(end -0.127 -0.8382)
			(stroke
				(width 0.1524)
				(type default)
			)
			(layer "F.SilkS")
		)
		(fp_line
			(start -1.905 0.8382)
			(end -1.905 -0.8382)
			(stroke
				(width 0.1524)
				(type default)
			)
			(layer "F.SilkS")
		)
		(fp_line
			(start 1.905 0.8636)
			(end -1.905 0.8636)
			(stroke
				(width 0.1524)
				(type default)
			)
			(layer "F.SilkS")
		)
		(fp_rect
			(start -1.524 0.7112)
			(end 1.524 -0.7366)
			(stroke
				(width 0)
				(type default)
			)
			(fill no)
			(layer "F.CrtYd")
		)
		(pad "1" smd rect
			(at 0.94996 0 90)
			(size 1.1176 1.3716)
			(layers "F.Cu" "F.Mask" "F.Paste")
			(net "P3V3_10G_1_VCCR_L")
		)
		(pad "2" smd rect
			(at -0.94996 0 90)
			(size 1.1176 1.3716)
			(layers "F.Cu" "F.Mask" "F.Paste")
			(net "P3V3_10G_1_VCCR")
		)
	)
	(footprint ""
		(layer "F.Cu")
		(at 376.099832 -41.221914)
		(property "Reference" "FS5"
			(at 35.30854 24.241252 0)
			(unlocked yes)
			(layer "F.SilkS")
			(effects
				(font
					(size 0.7874 0.5842)
					(thickness 0.1524)
				)
				(justify left)
			)
		)
		(property "Value" ""
			(at 0 0 0)
			(layer "F.Fab")
			(effects
				(font
					(size 1.27 1.27)
				)
			)
		)
		(duplicate_pad_numbers_are_jumpers no)
		(fp_line
			(start -0.650494 -1.050036)
			(end 3.550412 -1.050036)
			(stroke
				(width 0.1524)
				(type default)
			)
			(layer "F.SilkS")
		)
		(fp_line
			(start -0.650494 1.050036)
			(end -0.650494 -1.050036)
			(stroke
				(width 0.1524)
				(type default)
			)
			(layer "F.SilkS")
		)
		(fp_line
			(start 3.550412 -1.050036)
			(end 3.550412 1.050036)
			(stroke
				(width 0.1524)
				(type default)
			)
			(layer "F.SilkS")
		)
		(fp_line
			(start 3.550412 1.050036)
			(end -0.650494 1.050036)
			(stroke
				(width 0.1524)
				(type default)
			)
			(layer "F.SilkS")
		)
		(fp_poly
			(pts
				(xy 3.228086 -0.9652) (xy 3.228086 -1.100074) (xy -0.327914 -1.100074) (xy -0.327914 -0.9652) (xy -0.556514 -0.9652)
				(xy -0.556514 0.9652) (xy -0.327914 0.9652) (xy -0.327914 1.100074) (xy 3.228086 1.100074) (xy 3.228086 0.9652)
				(xy 3.456686 0.9652) (xy 3.456686 -0.9652)
			)
			(stroke
				(width 0)
				(type default)
			)
			(fill no)
			(layer "F.CrtYd")
		)
		(fp_text user "1"
			(at -0.315214 -1.946148 0)
			(unlocked yes)
			(layer "F.SilkS")
			(effects
				(font
					(size 0.7874 0.5842)
					(thickness 0.1524)
				)
				(justify left)
			)
		)
		(fp_text user "2"
			(at 4.028186 -0.066548 0)
			(unlocked yes)
			(layer "F.SilkS")
			(effects
				(font
					(size 0.7874 0.5842)
					(thickness 0.1524)
				)
				(justify left)
			)
		)
		(pad "1" smd rect
			(at 0 0)
			(size 1.016 1.8034)
			(layers "F.Cu" "F.Mask" "F.Paste")
			(net "P3V3_BLAD2")
		)
		(pad "2" smd rect
			(at 2.899918 0)
			(size 1.016 1.8034)
			(layers "F.Cu" "F.Mask" "F.Paste")
			(net "P3V3_10G_3_VCCT_L")
		)
	)
	(footprint ""
		(layer "F.Cu")
		(at 92.16644 -29.122878)
		(property "Reference" "R4"
			(at -7.0866 1.025652 0)
			(unlocked yes)
			(layer "F.SilkS")
			(effects
				(font
					(size 0.7874 0.5842)
					(thickness 0.1524)
				)
				(justify left)
			)
		)
		(property "Value" ""
			(at 0 0 0)
			(layer "F.Fab")
			(effects
				(font
					(size 1.27 1.27)
				)
			)
		)
		(duplicate_pad_numbers_are_jumpers no)
		(fp_line
			(start -0.7874 -0.4064)
			(end 0.7874 -0.4064)
			(stroke
				(width 0.1524)
				(type default)
			)
			(layer "F.SilkS")
		)
		(fp_line
			(start -0.7874 0.4064)
			(end -0.7874 -0.4064)
			(stroke
				(width 0.1524)
				(type default)
			)
			(layer "F.SilkS")
		)
		(fp_line
			(start 0.7874 -0.4064)
			(end 0.7874 0.4064)
			(stroke
				(width 0.1524)
				(type default)
			)
			(layer "F.SilkS")
		)
		(fp_line
			(start 0.7874 0.4064)
			(end -0.7874 0.4064)
			(stroke
				(width 0.1524)
				(type default)
			)
			(layer "F.SilkS")
		)
		(fp_poly
			(pts
				(xy -0.508 0.2794) (xy -0.508 0.2286) (xy -0.635 0.2286) (xy -0.635 -0.254) (xy -0.5334 -0.254)
				(xy -0.5334 -0.2794) (xy 0.5334 -0.2794) (xy 0.5334 -0.254) (xy 0.635 -0.254) (xy 0.635 0.254) (xy 0.5334 0.254)
				(xy 0.5334 0.2794)
			)
			(stroke
				(width 0)
				(type default)
			)
			(fill no)
			(layer "F.CrtYd")
		)
		(pad "1" smd rect
			(at 0.40005 0)
			(size 0.4572 0.508)
			(layers "F.Cu" "F.Mask" "F.Paste")
			(net "P3V3_BLAD1")
		)
		(pad "2" smd rect
			(at -0.40005 0)
			(size 0.4572 0.508)
			(layers "F.Cu" "F.Mask" "F.Paste")
			(net "ENET10G_2_TX_DIS")
		)
	)
)
